(kicad_pcb
	(version 20260206)
	(generator "pcbnew")
	(generator_version "10.0")
	(general
		(thickness 1.6)
		(legacy_teardrops no)
	)
	(paper "A4")
	(title_block
		(title "03242023_DA0F0TMBIJ0_F0T_Motherboard_J_brd_V01_OCP.brd")
		(comment 1 "Grand Teton / footprints 194-199 of 6105")
	)
	(layers
		(0 "F.Cu" signal "TOP")
		(4 "In1.Cu" signal "GND")
		(6 "In2.Cu" signal "IN1")
		(8 "In3.Cu" signal "GND1")
		(10 "In4.Cu" signal "IN2")
		(12 "In5.Cu" signal "GND2")
		(14 "In6.Cu" signal "IN3")
		(16 "In7.Cu" signal "GND3")
		(18 "In8.Cu" signal "VCC")
		(20 "In9.Cu" signal "VCC1")
		(22 "In10.Cu" signal "GND4")
		(24 "In11.Cu" signal "IN4")
		(26 "In12.Cu" signal "GND5")
		(28 "In13.Cu" signal "IN5")
		(30 "In14.Cu" signal "GND6")
		(32 "In15.Cu" signal "IN6")
		(34 "In16.Cu" signal "GND7")
		(2 "B.Cu" signal "BOTTOM")
		(9 "F.Adhes" user "F.Adhesive")
		(11 "B.Adhes" user "B.Adhesive")
		(13 "F.Paste" user "Package Geometry/Pastemask Top")
		(15 "B.Paste" user "Package Geometry/Pastemask Bottom")
		(5 "F.SilkS" user "Ref Des/Silkscreen Top")
		(7 "B.SilkS" user "Ref Des/Silkscreen Bottom")
		(1 "F.Mask" user "Board Geometry/Soldermask Top")
		(3 "B.Mask" user "Board Geometry/Soldermask Bottom")
		(17 "Dwgs.User" user "User.Drawings")
		(19 "Cmts.User" user "User.Comments")
		(21 "Eco1.User" user "User.Eco1")
		(23 "Eco2.User" user "User.Eco2")
		(25 "Edge.Cuts" user "Board Geometry/Outline")
		(27 "Margin" user)
		(31 "F.CrtYd" user "Package Geometry/Place Bound Top")
		(29 "B.CrtYd" user "Package Geometry/Place Bound Bottom")
		(35 "F.Fab" user "Ref Des/Assembly Top")
		(33 "B.Fab" user "Ref Des/Assembly Bottom")
	)
	(footprint ""
		(layer "F.Cu")
		(at 114.660934 -113.157762 -90)
		(property "Reference" "U304"
			(at -0.219456 -2.976626 0)
			(unlocked yes)
			(layer "F.SilkS")
			(effects
				(font
					(size 0.7874 0.5842)
					(thickness 0.1524)
				)
				(justify left)
			)
		)
		(property "Value" ""
			(at 0 0 270)
			(layer "F.Fab")
			(effects
				(font
					(size 1.27 1.27)
				)
			)
		)
		(duplicate_pad_numbers_are_jumpers no)
		(fp_line
			(start -2.0066 2.5527)
			(end -2.0066 -2.5527)
			(stroke
				(width 0.1524)
				(type default)
			)
			(layer "F.SilkS")
		)
		(fp_line
			(start 2.0066 2.5527)
			(end -2.0066 2.5527)
			(stroke
				(width 0.1524)
				(type default)
			)
			(layer "F.SilkS")
		)
		(fp_line
			(start 0 -1.9812)
			(end 0.5715 -2.5527)
			(stroke
				(width 0.1524)
				(type default)
			)
			(layer "F.SilkS")
		)
		(fp_line
			(start -2.0066 -2.5527)
			(end -0.5715 -2.5527)
			(stroke
				(width 0.1524)
				(type default)
			)
			(layer "F.SilkS")
		)
		(fp_line
			(start -0.5715 -2.5527)
			(end 0 -1.9812)
			(stroke
				(width 0.1524)
				(type default)
			)
			(layer "F.SilkS")
		)
		(fp_line
			(start 0.5715 -2.5527)
			(end 2.0066 -2.5527)
			(stroke
				(width 0.1524)
				(type default)
			)
			(layer "F.SilkS")
		)
		(fp_line
			(start 2.0066 -2.5527)
			(end 2.0066 2.5527)
			(stroke
				(width 0.1524)
				(type default)
			)
			(layer "F.SilkS")
		)
		(fp_poly
			(pts
				(xy -4.36372 -2.233168) (xy -3.81 -1.905) (xy -4.36372 -1.608328)
			)
			(stroke
				(width 0)
				(type default)
			)
			(fill yes)
			(layer "F.SilkS")
		)
		(fp_line
			(start -2.249932 2.549906)
			(end -2.249932 -2.549906)
			(stroke
				(width 0.1)
				(type default)
			)
			(layer "F.Fab")
		)
		(fp_line
			(start 2.249932 2.549906)
			(end -2.249932 2.549906)
			(stroke
				(width 0.1)
				(type default)
			)
			(layer "F.Fab")
		)
		(fp_line
			(start -2.249932 -2.549906)
			(end 2.249932 -2.549906)
			(stroke
				(width 0.1)
				(type default)
			)
			(layer "F.Fab")
		)
		(fp_line
			(start 2.249932 -2.549906)
			(end 2.249932 2.549906)
			(stroke
				(width 0.1)
				(type default)
			)
			(layer "F.Fab")
		)
		(fp_poly
			(pts
				(xy -4.36372 -1.608328) (xy -4.36372 -2.233168) (xy -3.81 -1.905)
			)
			(stroke
				(width 0)
				(type default)
			)
			(fill yes)
			(layer "F.Fab")
		)
		(pad "1" smd rect
			(at -2.921 -1.949958 180)
			(size 0.3556 1.4986)
			(layers "F.Cu" "F.Mask" "F.Paste")
			(net "PD_GTL2014_BMC_JTAG_DIR_0")
		)
		(pad "2" smd rect
			(at -2.921 -1.299972 180)
			(size 0.3556 1.4986)
			(layers "F.Cu" "F.Mask" "F.Paste")
			(net "RST_CPU0_DRAM_GH_PLD_N")
		)
		(pad "3" smd rect
			(at -2.921 -0.649986 180)
			(size 0.3556 1.4986)
			(layers "F.Cu" "F.Mask" "F.Paste")
			(net "RST_CPU0_DRAM_EF_PLD_N")
		)
		(pad "4" smd rect
			(at -2.921 0 180)
			(size 0.3556 1.4986)
			(layers "F.Cu" "F.Mask" "F.Paste")
			(net "P0V62_CPU0_RST_DDR_VREF")
		)
		(pad "5" smd rect
			(at -2.921 0.649986 180)
			(size 0.3556 1.4986)
			(layers "F.Cu" "F.Mask" "F.Paste")
			(net "RST_CPU0_DRAM_CD_PLD_N")
		)
		(pad "6" smd rect
			(at -2.921 1.299972 180)
			(size 0.3556 1.4986)
			(layers "F.Cu" "F.Mask" "F.Paste")
			(net "RST_CPU0_DRAM_AB_PLD_N")
		)
		(pad "7" smd rect
			(at -2.921 1.949958 180)
			(size 0.3556 1.4986)
			(layers "F.Cu" "F.Mask" "F.Paste")
			(net "GND")
		)
		(pad "8" smd rect
			(at 2.921 1.949958 180)
			(size 0.3556 1.4986)
			(layers "F.Cu" "F.Mask" "F.Paste")
			(net "GND")
		)
		(pad "9" smd rect
			(at 2.921 1.299972 180)
			(size 0.3556 1.4986)
			(layers "F.Cu" "F.Mask" "F.Paste")
			(net "RST_CPU0_DRAM_AB_PLD_LVT3_R_N")
		)
		(pad "10" smd rect
			(at 2.921 0.649986 180)
			(size 0.3556 1.4986)
			(layers "F.Cu" "F.Mask" "F.Paste")
			(net "RST_CPU0_DRAM_CD_PLD_LVT3_R_N")
		)
		(pad "11" smd rect
			(at 2.921 0 180)
			(size 0.3556 1.4986)
			(layers "F.Cu" "F.Mask" "F.Paste")
			(net "GND")
		)
		(pad "12" smd rect
			(at 2.921 -0.649986 180)
			(size 0.3556 1.4986)
			(layers "F.Cu" "F.Mask" "F.Paste")
			(net "RST_CPU0_DRAM_EF_PLD_LVT3_R_N")
		)
		(pad "13" smd rect
			(at 2.921 -1.299972 180)
			(size 0.3556 1.4986)
			(layers "F.Cu" "F.Mask" "F.Paste")
			(net "RST_CPU0_DRAM_GH_PLD_LVT3_R_N")
		)
		(pad "14" smd rect
			(at 2.921 -1.949958 180)
			(size 0.3556 1.4986)
			(layers "F.Cu" "F.Mask" "F.Paste")
			(net "P3V3_AUX")
		)
	)
	(footprint ""
		(layer "F.Cu")
		(at 461.593946 -107.043728)
		(property "Reference" "C592"
			(at 0 0 0)
			(layer "F.SilkS")
			(hide yes)
			(effects
				(font
					(size 1.27 1.27)
				)
			)
		)
		(property "Value" ""
			(at 0 0 0)
			(layer "F.Fab")
			(effects
				(font
					(size 1.27 1.27)
				)
			)
		)
		(duplicate_pad_numbers_are_jumpers no)
		(fp_line
			(start -0.7874 -0.4064)
			(end 0.7874 -0.4064)
			(stroke
				(width 0.1524)
				(type default)
			)
			(layer "F.SilkS")
		)
		(fp_line
			(start -0.7874 0.4064)
			(end -0.7874 -0.4064)
			(stroke
				(width 0.1524)
				(type default)
			)
			(layer "F.SilkS")
		)
		(fp_line
			(start 0.7874 -0.4064)
			(end 0.7874 0.4064)
			(stroke
				(width 0.1524)
				(type default)
			)
			(layer "F.SilkS")
		)
		(fp_line
			(start 0.7874 0.4064)
			(end -0.7874 0.4064)
			(stroke
				(width 0.1524)
				(type default)
			)
			(layer "F.SilkS")
		)
		(fp_line
			(start -0.67945 -0.305054)
			(end -0.12065 -0.305054)
			(stroke
				(width 0.1)
				(type default)
			)
			(layer "F.Fab")
		)
		(fp_line
			(start -0.67945 0.3048)
			(end -0.67945 -0.305054)
			(stroke
				(width 0.1)
				(type default)
			)
			(layer "F.Fab")
		)
		(fp_line
			(start -0.12065 -0.305054)
			(end -0.12065 -0.2794)
			(stroke
				(width 0.1)
				(type default)
			)
			(layer "F.Fab")
		)
		(fp_line
			(start -0.12065 -0.2794)
			(end 0.12065 -0.2794)
			(stroke
				(width 0.1)
				(type default)
			)
			(layer "F.Fab")
		)
		(fp_line
			(start -0.12065 0.2794)
			(end -0.12065 0.3048)
			(stroke
				(width 0.1)
				(type default)
			)
			(layer "F.Fab")
		)
		(fp_line
			(start -0.12065 0.3048)
			(end -0.67945 0.3048)
			(stroke
				(width 0.1)
				(type default)
			)
			(layer "F.Fab")
		)
		(fp_line
			(start 0.120396 0.2794)
			(end -0.12065 0.2794)
			(stroke
				(width 0.1)
				(type default)
			)
			(layer "F.Fab")
		)
		(fp_line
			(start 0.120396 0.3048)
			(end 0.120396 0.2794)
			(stroke
				(width 0.1)
				(type default)
			)
			(layer "F.Fab")
		)
		(fp_line
			(start 0.12065 -0.3048)
			(end 0.67945 -0.3048)
			(stroke
				(width 0.1)
				(type default)
			)
			(layer "F.Fab")
		)
		(fp_line
			(start 0.12065 -0.2794)
			(end 0.12065 -0.3048)
			(stroke
				(width 0.1)
				(type default)
			)
			(layer "F.Fab")
		)
		(fp_line
			(start 0.67945 -0.3048)
			(end 0.67945 0.3048)
			(stroke
				(width 0.1)
				(type default)
			)
			(layer "F.Fab")
		)
		(fp_line
			(start 0.67945 0.3048)
			(end 0.120396 0.3048)
			(stroke
				(width 0.1)
				(type default)
			)
			(layer "F.Fab")
		)
		(pad "1" smd circle
			(at -0.40005 0)
			(size 0 0)
			(layers "F.Cu" "F.Mask" "F.Paste")
			(net "P3V3_AUX")
		)
		(pad "2" smd circle
			(at 0.40005 0)
			(size 0 0)
			(layers "F.Cu" "F.Mask" "F.Paste")
			(net "GND")
		)
	)
	(footprint ""
		(layer "F.Cu")
		(at 194.22618 -80.627728)
		(property "Reference" "R366"
			(at 0 0 0)
			(layer "F.SilkS")
			(hide yes)
			(effects
				(font
					(size 1.27 1.27)
				)
			)
		)
		(property "Value" ""
			(at 0 0 0)
			(layer "F.Fab")
			(effects
				(font
					(size 1.27 1.27)
				)
			)
		)
		(duplicate_pad_numbers_are_jumpers no)
		(fp_line
			(start -0.7874 -0.4064)
			(end 0.7874 -0.4064)
			(stroke
				(width 0.1524)
				(type default)
			)
			(layer "F.SilkS")
		)
		(fp_line
			(start -0.7874 0.4064)
			(end -0.7874 -0.4064)
			(stroke
				(width 0.1524)
				(type default)
			)
			(layer "F.SilkS")
		)
		(fp_line
			(start 0.7874 -0.4064)
			(end 0.7874 0.4064)
			(stroke
				(width 0.1524)
				(type default)
			)
			(layer "F.SilkS")
		)
		(fp_line
			(start 0.7874 0.4064)
			(end -0.7874 0.4064)
			(stroke
				(width 0.1524)
				(type default)
			)
			(layer "F.SilkS")
		)
		(fp_line
			(start -0.67945 -0.305054)
			(end -0.12065 -0.305054)
			(stroke
				(width 0.1)
				(type default)
			)
			(layer "F.Fab")
		)
		(fp_line
			(start -0.67945 0.3048)
			(end -0.67945 -0.305054)
			(stroke
				(width 0.1)
				(type default)
			)
			(layer "F.Fab")
		)
		(fp_line
			(start -0.12065 -0.305054)
			(end -0.12065 -0.2794)
			(stroke
				(width 0.1)
				(type default)
			)
			(layer "F.Fab")
		)
		(fp_line
			(start -0.12065 -0.2794)
			(end 0.12065 -0.2794)
			(stroke
				(width 0.1)
				(type default)
			)
			(layer "F.Fab")
		)
		(fp_line
			(start -0.12065 0.2794)
			(end -0.12065 0.3048)
			(stroke
				(width 0.1)
				(type default)
			)
			(layer "F.Fab")
		)
		(fp_line
			(start -0.12065 0.3048)
			(end -0.67945 0.3048)
			(stroke
				(width 0.1)
				(type default)
			)
			(layer "F.Fab")
		)
		(fp_line
			(start 0.120396 0.2794)
			(end -0.12065 0.2794)
			(stroke
				(width 0.1)
				(type default)
			)
			(layer "F.Fab")
		)
		(fp_line
			(start 0.120396 0.3048)
			(end 0.120396 0.2794)
			(stroke
				(width 0.1)
				(type default)
			)
			(layer "F.Fab")
		)
		(fp_line
			(start 0.12065 -0.3048)
			(end 0.67945 -0.3048)
			(stroke
				(width 0.1)
				(type default)
			)
			(layer "F.Fab")
		)
		(fp_line
			(start 0.12065 -0.2794)
			(end 0.12065 -0.3048)
			(stroke
				(width 0.1)
				(type default)
			)
			(layer "F.Fab")
		)
		(fp_line
			(start 0.67945 -0.3048)
			(end 0.67945 0.3048)
			(stroke
				(width 0.1)
				(type default)
			)
			(layer "F.Fab")
		)
		(fp_line
			(start 0.67945 0.3048)
			(end 0.120396 0.3048)
			(stroke
				(width 0.1)
				(type default)
			)
			(layer "F.Fab")
		)
		(pad "1" smd circle
			(at -0.40005 0)
			(size 0 0)
			(layers "F.Cu" "F.Mask" "F.Paste")
			(net "P3V3_AUX")
		)
		(pad "2" smd circle
			(at 0.40005 0)
			(size 0 0)
			(layers "F.Cu" "F.Mask" "F.Paste")
			(net "LED_CPU_RMCA_CATERR")
		)
	)
	(footprint ""
		(layer "F.Cu")
		(at 419.1762 -16.088614 90)
		(property "Reference" "C858"
			(at 0 0 90)
			(layer "F.SilkS")
			(hide yes)
			(effects
				(font
					(size 1.27 1.27)
				)
			)
		)
		(property "Value" ""
			(at 0 0 90)
			(layer "F.Fab")
			(effects
				(font
					(size 1.27 1.27)
				)
			)
		)
		(duplicate_pad_numbers_are_jumpers no)
		(fp_line
			(start 0.299974 -0.150114)
			(end 0.299974 0.150114)
			(stroke
				(width 0.1)
				(type default)
			)
			(layer "F.Fab")
		)
		(fp_line
			(start -0.299974 -0.150114)
			(end 0.299974 -0.150114)
			(stroke
				(width 0.1)
				(type default)
			)
			(layer "F.Fab")
		)
		(fp_line
			(start 0.299974 0.150114)
			(end -0.299974 0.150114)
			(stroke
				(width 0.1)
				(type default)
			)
			(layer "F.Fab")
		)
		(fp_line
			(start -0.299974 0.150114)
			(end -0.299974 -0.150114)
			(stroke
				(width 0.1)
				(type default)
			)
			(layer "F.Fab")
		)
		(pad "1" smd rect
			(at -0.2667 0 90)
			(size 0.3048 0.381)
			(layers "F.Cu" "F.Mask" "F.Paste")
			(net "P5E_CPU0_PE1_TX_C_DN<5>")
		)
		(pad "2" smd rect
			(at 0.2667 0 90)
			(size 0.3048 0.381)
			(layers "F.Cu" "F.Mask" "F.Paste")
			(net "P5E_CPU0_PE1_TX_DN<5>")
		)
	)
	(footprint ""
		(layer "F.Cu")
		(at 22.809454 -112.399826)
		(property "Reference" "R3671"
			(at 0 0 0)
			(layer "F.SilkS")
			(hide yes)
			(effects
				(font
					(size 1.27 1.27)
				)
			)
		)
		(property "Value" ""
			(at 0 0 0)
			(layer "F.Fab")
			(effects
				(font
					(size 1.27 1.27)
				)
			)
		)
		(duplicate_pad_numbers_are_jumpers no)
		(fp_line
			(start -0.7874 -0.4064)
			(end 0.7874 -0.4064)
			(stroke
				(width 0.1524)
				(type default)
			)
			(layer "F.SilkS")
		)
		(fp_line
			(start -0.7874 0.4064)
			(end -0.7874 -0.4064)
			(stroke
				(width 0.1524)
				(type default)
			)
			(layer "F.SilkS")
		)
		(fp_line
			(start 0.7874 -0.4064)
			(end 0.7874 0.4064)
			(stroke
				(width 0.1524)
				(type default)
			)
			(layer "F.SilkS")
		)
		(fp_line
			(start 0.7874 0.4064)
			(end -0.7874 0.4064)
			(stroke
				(width 0.1524)
				(type default)
			)
			(layer "F.SilkS")
		)
		(fp_line
			(start -0.67945 -0.305054)
			(end -0.12065 -0.305054)
			(stroke
				(width 0.1)
				(type default)
			)
			(layer "F.Fab")
		)
		(fp_line
			(start -0.67945 0.3048)
			(end -0.67945 -0.305054)
			(stroke
				(width 0.1)
				(type default)
			)
			(layer "F.Fab")
		)
		(fp_line
			(start -0.12065 -0.305054)
			(end -0.12065 -0.2794)
			(stroke
				(width 0.1)
				(type default)
			)
			(layer "F.Fab")
		)
		(fp_line
			(start -0.12065 -0.2794)
			(end 0.12065 -0.2794)
			(stroke
				(width 0.1)
				(type default)
			)
			(layer "F.Fab")
		)
		(fp_line
			(start -0.12065 0.2794)
			(end -0.12065 0.3048)
			(stroke
				(width 0.1)
				(type default)
			)
			(layer "F.Fab")
		)
		(fp_line
			(start -0.12065 0.3048)
			(end -0.67945 0.3048)
			(stroke
				(width 0.1)
				(type default)
			)
			(layer "F.Fab")
		)
		(fp_line
			(start 0.120396 0.2794)
			(end -0.12065 0.2794)
			(stroke
				(width 0.1)
				(type default)
			)
			(layer "F.Fab")
		)
		(fp_line
			(start 0.120396 0.3048)
			(end 0.120396 0.2794)
			(stroke
				(width 0.1)
				(type default)
			)
			(layer "F.Fab")
		)
		(fp_line
			(start 0.12065 -0.3048)
			(end 0.67945 -0.3048)
			(stroke
				(width 0.1)
				(type default)
			)
			(layer "F.Fab")
		)
		(fp_line
			(start 0.12065 -0.2794)
			(end 0.12065 -0.3048)
			(stroke
				(width 0.1)
				(type default)
			)
			(layer "F.Fab")
		)
		(fp_line
			(start 0.67945 -0.3048)
			(end 0.67945 0.3048)
			(stroke
				(width 0.1)
				(type default)
			)
			(layer "F.Fab")
		)
		(fp_line
			(start 0.67945 0.3048)
			(end 0.120396 0.3048)
			(stroke
				(width 0.1)
				(type default)
			)
			(layer "F.Fab")
		)
		(pad "1" smd circle
			(at -0.40005 0)
			(size 0 0)
			(layers "F.Cu" "F.Mask" "F.Paste")
			(net "SMB_VR_3V3AUX_SDA_R1")
		)
		(pad "2" smd circle
			(at 0.40005 0)
			(size 0 0)
			(layers "F.Cu" "F.Mask" "F.Paste")
			(net "SMB_SEN_TIC_3V3AUX_SDA")
		)
	)
	(footprint ""
		(layer "F.Cu")
		(at 104.8258 -407.289 180)
		(property "Reference" "C2372"
			(at 0 0 180)
			(layer "F.SilkS")
			(hide yes)
			(effects
				(font
					(size 1.27 1.27)
				)
			)
		)
		(property "Value" ""
			(at 0 0 180)
			(layer "F.Fab")
			(effects
				(font
					(size 1.27 1.27)
				)
			)
		)
		(duplicate_pad_numbers_are_jumpers no)
		(fp_line
			(start 0.7874 0.4064)
			(end -0.7874 0.4064)
			(stroke
				(width 0.1524)
				(type default)
			)
			(layer "F.SilkS")
		)
		(fp_line
			(start 0.7874 -0.4064)
			(end 0.7874 0.4064)
			(stroke
				(width 0.1524)
				(type default)
			)
			(layer "F.SilkS")
		)
		(fp_line
			(start -0.7874 0.4064)
			(end -0.7874 -0.4064)
			(stroke
				(width 0.1524)
				(type default)
			)
			(layer "F.SilkS")
		)
		(fp_line
			(start -0.7874 -0.4064)
			(end 0.7874 -0.4064)
			(stroke
				(width 0.1524)
				(type default)
			)
			(layer "F.SilkS")
		)
		(fp_line
			(start 0.67945 0.3048)
			(end 0.120396 0.3048)
			(stroke
				(width 0.1)
				(type default)
			)
			(layer "F.Fab")
		)
		(fp_line
			(start 0.67945 -0.3048)
			(end 0.67945 0.3048)
			(stroke
				(width 0.1)
				(type default)
			)
			(layer "F.Fab")
		)
		(fp_line
			(start 0.12065 -0.2794)
			(end 0.12065 -0.3048)
			(stroke
				(width 0.1)
				(type default)
			)
			(layer "F.Fab")
		)
		(fp_line
			(start 0.12065 -0.3048)
			(end 0.67945 -0.3048)
			(stroke
				(width 0.1)
				(type default)
			)
			(layer "F.Fab")
		)
		(fp_line
			(start 0.120396 0.3048)
			(end 0.120396 0.2794)
			(stroke
				(width 0.1)
				(type default)
			)
			(layer "F.Fab")
		)
		(fp_line
			(start 0.120396 0.2794)
			(end -0.12065 0.2794)
			(stroke
				(width 0.1)
				(type default)
			)
			(layer "F.Fab")
		)
		(fp_line
			(start -0.12065 0.3048)
			(end -0.67945 0.3048)
			(stroke
				(width 0.1)
				(type default)
			)
			(layer "F.Fab")
		)
		(fp_line
			(start -0.12065 0.2794)
			(end -0.12065 0.3048)
			(stroke
				(width 0.1)
				(type default)
			)
			(layer "F.Fab")
		)
		(fp_line
			(start -0.12065 -0.2794)
			(end 0.12065 -0.2794)
			(stroke
				(width 0.1)
				(type default)
			)
			(layer "F.Fab")
		)
		(fp_line
			(start -0.12065 -0.305054)
			(end -0.12065 -0.2794)
			(stroke
				(width 0.1)
				(type default)
			)
			(layer "F.Fab")
		)
		(fp_line
			(start -0.67945 0.3048)
			(end -0.67945 -0.305054)
			(stroke
				(width 0.1)
				(type default)
			)
			(layer "F.Fab")
		)
		(fp_line
			(start -0.67945 -0.305054)
			(end -0.12065 -0.305054)
			(stroke
				(width 0.1)
				(type default)
			)
			(layer "F.Fab")
		)
		(pad "1" smd circle
			(at -0.40005 0 180)
			(size 0 0)
			(layers "F.Cu" "F.Mask" "F.Paste")
			(net "PRSNT_SWB_ISO_N")
		)
		(pad "2" smd circle
			(at 0.40005 0 180)
			(size 0 0)
			(layers "F.Cu" "F.Mask" "F.Paste")
			(net "GND")
		)
	)
)
